# S9S_MB_2U (Grand Teton) — schematic netlist excerpt (pin names and nets, part order shuffled) for the footprints in the layout excerpt that follows; sources: Cadence DE-HDL packaged netlist, KiCad conversion of 03242023_DA0F0TMBIJ0_F0T_Motherboard_J_brd_V01_OCP.brd

R3144  Q_RES  0 5% EMPTY  pkg 0402LF  page 156 : A = P12V_OCP_PWRGD_1 ; B = HP_LVC3_OCP_V3_1_P12V_PWRGD
C1556  Q_CAP_DIFFBUS  DIFF BUS_0.22UF 6.3V 20% X6S  pkg C0201  page 175 : \1\ = P5E_CPU0_PE4_TX_C_DN<11> ; \2\ = P5E_CPU0_PE4_TX_DN<11>
R978  Q_RES  560 1% CHIP  pkg 0402LF  page 236 : A = P3V3_AUX ; B = SMB_S3M_CPU1_3V3AUX_SCL

(kicad_pcb
	(version 20260206)
	(generator "pcbnew")
	(generator_version "10.0")
	(general
		(thickness 1.6)
		(legacy_teardrops no)
	)
	(paper "A4")
	(title_block
		(title "03242023_DA0F0TMBIJ0_F0T_Motherboard_J_brd_V01_OCP.brd")
		(comment 1 "Grand Teton / footprints 2087-2089 of 6105")
	)
	(layers
		(0 "F.Cu" signal "TOP")
		(4 "In1.Cu" signal "GND")
		(6 "In2.Cu" signal "IN1")
		(8 "In3.Cu" signal "GND1")
		(10 "In4.Cu" signal "IN2")
		(12 "In5.Cu" signal "GND2")
		(14 "In6.Cu" signal "IN3")
		(16 "In7.Cu" signal "GND3")
		(18 "In8.Cu" signal "VCC")
		(20 "In9.Cu" signal "VCC1")
		(22 "In10.Cu" signal "GND4")
		(24 "In11.Cu" signal "IN4")
		(26 "In12.Cu" signal "GND5")
		(28 "In13.Cu" signal "IN5")
		(30 "In14.Cu" signal "GND6")
		(32 "In15.Cu" signal "IN6")
		(34 "In16.Cu" signal "GND7")
		(2 "B.Cu" signal "BOTTOM")
		(9 "F.Adhes" user "F.Adhesive")
		(11 "B.Adhes" user "B.Adhesive")
		(13 "F.Paste" user "Package Geometry/Pastemask Top")
		(15 "B.Paste" user "Package Geometry/Pastemask Bottom")
		(5 "F.SilkS" user "Ref Des/Silkscreen Top")
		(7 "B.SilkS" user "Ref Des/Silkscreen Bottom")
		(1 "F.Mask" user "Board Geometry/Soldermask Top")
		(3 "B.Mask" user "Board Geometry/Soldermask Bottom")
		(17 "Dwgs.User" user "User.Drawings")
		(19 "Cmts.User" user "User.Comments")
		(21 "Eco1.User" user "User.Eco1")
		(23 "Eco2.User" user "User.Eco2")
		(25 "Edge.Cuts" user "Board Geometry/Outline")
		(27 "Margin" user)
		(31 "F.CrtYd" user "Package Geometry/Place Bound Top")
		(29 "B.CrtYd" user "Package Geometry/Place Bound Bottom")
		(35 "F.Fab" user "Ref Des/Assembly Top")
		(33 "B.Fab" user "Ref Des/Assembly Bottom")
	)
	(footprint ""
		(layer "F.Cu")
		(at 454.447402 -18.030698)
		(property "Reference" "R3144"
			(at 0 0 0)
			(layer "F.SilkS")
			(hide yes)
			(effects
				(font
					(size 1.27 1.27)
				)
			)
		)
		(property "Value" ""
			(at 0 0 0)
			(layer "F.Fab")
			(effects
				(font
					(size 1.27 1.27)
				)
			)
		)
		(duplicate_pad_numbers_are_jumpers no)
		(fp_line
			(start -0.7874 -0.4064)
			(end 0.7874 -0.4064)
			(stroke
				(width 0.1524)
				(type default)
			)
			(layer "F.SilkS")
		)
		(fp_line
			(start -0.7874 0.4064)
			(end -0.7874 -0.4064)
			(stroke
				(width 0.1524)
				(type default)
			)
			(layer "F.SilkS")
		)
		(fp_line
			(start 0.7874 -0.4064)
			(end 0.7874 0.4064)
			(stroke
				(width 0.1524)
				(type default)
			)
			(layer "F.SilkS")
		)
		(fp_line
			(start 0.7874 0.4064)
			(end -0.7874 0.4064)
			(stroke
				(width 0.1524)
				(type default)
			)
			(layer "F.SilkS")
		)
		(fp_line
			(start -0.67945 -0.305054)
			(end -0.12065 -0.305054)
			(stroke
				(width 0.1)
				(type default)
			)
			(layer "F.Fab")
		)
		(fp_line
			(start -0.67945 0.3048)
			(end -0.67945 -0.305054)
			(stroke
				(width 0.1)
				(type default)
			)
			(layer "F.Fab")
		)
		(fp_line
			(start -0.12065 -0.305054)
			(end -0.12065 -0.2794)
			(stroke
				(width 0.1)
				(type default)
			)
			(layer "F.Fab")
		)
		(fp_line
			(start -0.12065 -0.2794)
			(end 0.12065 -0.2794)
			(stroke
				(width 0.1)
				(type default)
			)
			(layer "F.Fab")
		)
		(fp_line
			(start -0.12065 0.2794)
			(end -0.12065 0.3048)
			(stroke
				(width 0.1)
				(type default)
			)
			(layer "F.Fab")
		)
		(fp_line
			(start -0.12065 0.3048)
			(end -0.67945 0.3048)
			(stroke
				(width 0.1)
				(type default)
			)
			(layer "F.Fab")
		)
		(fp_line
			(start 0.120396 0.2794)
			(end -0.12065 0.2794)
			(stroke
				(width 0.1)
				(type default)
			)
			(layer "F.Fab")
		)
		(fp_line
			(start 0.120396 0.3048)
			(end 0.120396 0.2794)
			(stroke
				(width 0.1)
				(type default)
			)
			(layer "F.Fab")
		)
		(fp_line
			(start 0.12065 -0.3048)
			(end 0.67945 -0.3048)
			(stroke
				(width 0.1)
				(type default)
			)
			(layer "F.Fab")
		)
		(fp_line
			(start 0.12065 -0.2794)
			(end 0.12065 -0.3048)
			(stroke
				(width 0.1)
				(type default)
			)
			(layer "F.Fab")
		)
		(fp_line
			(start 0.67945 -0.3048)
			(end 0.67945 0.3048)
			(stroke
				(width 0.1)
				(type default)
			)
			(layer "F.Fab")
		)
		(fp_line
			(start 0.67945 0.3048)
			(end 0.120396 0.3048)
			(stroke
				(width 0.1)
				(type default)
			)
			(layer "F.Fab")
		)
		(pad "1" smd circle
			(at -0.40005 0)
			(size 0 0)
			(layers "F.Cu" "F.Mask" "F.Paste")
			(net "P12V_OCP_PWRGD_1")
		)
		(pad "2" smd circle
			(at 0.40005 0)
			(size 0 0)
			(layers "F.Cu" "F.Mask" "F.Paste")
			(net "HP_LVC3_OCP_V3_1_P12V_PWRGD")
		)
	)
	(footprint ""
		(layer "F.Cu")
		(at 338.564728 -402.371052 -90)
		(property "Reference" "C1556"
			(at 0 0 270)
			(layer "F.SilkS")
			(hide yes)
			(effects
				(font
					(size 1.27 1.27)
				)
			)
		)
		(property "Value" ""
			(at 0 0 270)
			(layer "F.Fab")
			(effects
				(font
					(size 1.27 1.27)
				)
			)
		)
		(duplicate_pad_numbers_are_jumpers no)
		(fp_line
			(start -0.299974 0.150114)
			(end -0.299974 -0.150114)
			(stroke
				(width 0.1)
				(type default)
			)
			(layer "F.Fab")
		)
		(fp_line
			(start 0.299974 0.150114)
			(end -0.299974 0.150114)
			(stroke
				(width 0.1)
				(type default)
			)
			(layer "F.Fab")
		)
		(fp_line
			(start -0.299974 -0.150114)
			(end 0.299974 -0.150114)
			(stroke
				(width 0.1)
				(type default)
			)
			(layer "F.Fab")
		)
		(fp_line
			(start 0.299974 -0.150114)
			(end 0.299974 0.150114)
			(stroke
				(width 0.1)
				(type default)
			)
			(layer "F.Fab")
		)
		(pad "1" smd rect
			(at -0.2667 0 270)
			(size 0.3048 0.381)
			(layers "F.Cu" "F.Mask" "F.Paste")
			(net "P5E_CPU0_PE4_TX_C_DN<11>")
		)
		(pad "2" smd rect
			(at 0.2667 0 270)
			(size 0.3048 0.381)
			(layers "F.Cu" "F.Mask" "F.Paste")
			(net "P5E_CPU0_PE4_TX_DN<11>")
		)
	)
	(footprint ""
		(layer "F.Cu")
		(at 225.270568 -233.76255)
		(property "Reference" "R978"
			(at 0 0 0)
			(layer "F.SilkS")
			(hide yes)
			(effects
				(font
					(size 1.27 1.27)
				)
			)
		)
		(property "Value" ""
			(at 0 0 0)
			(layer "F.Fab")
			(effects
				(font
					(size 1.27 1.27)
				)
			)
		)
		(duplicate_pad_numbers_are_jumpers no)
		(fp_line
			(start -0.7874 -0.4064)
			(end 0.7874 -0.4064)
			(stroke
				(width 0.1524)
				(type default)
			)
			(layer "F.SilkS")
		)
		(fp_line
			(start -0.7874 0.4064)
			(end -0.7874 -0.4064)
			(stroke
				(width 0.1524)
				(type default)
			)
			(layer "F.SilkS")
		)
		(fp_line
			(start 0.7874 -0.4064)
			(end 0.7874 0.4064)
			(stroke
				(width 0.1524)
				(type default)
			)
			(layer "F.SilkS")
		)
		(fp_line
			(start 0.7874 0.4064)
			(end -0.7874 0.4064)
			(stroke
				(width 0.1524)
				(type default)
			)
			(layer "F.SilkS")
		)
		(fp_line
			(start -0.67945 -0.305054)
			(end -0.12065 -0.305054)
			(stroke
				(width 0.1)
				(type default)
			)
			(layer "F.Fab")
		)
		(fp_line
			(start -0.67945 0.3048)
			(end -0.67945 -0.305054)
			(stroke
				(width 0.1)
				(type default)
			)
			(layer "F.Fab")
		)
		(fp_line
			(start -0.12065 -0.305054)
			(end -0.12065 -0.2794)
			(stroke
				(width 0.1)
				(type default)
			)
			(layer "F.Fab")
		)
		(fp_line
			(start -0.12065 -0.2794)
			(end 0.12065 -0.2794)
			(stroke
				(width 0.1)
				(type default)
			)
			(layer "F.Fab")
		)
		(fp_line
			(start -0.12065 0.2794)
			(end -0.12065 0.3048)
			(stroke
				(width 0.1)
				(type default)
			)
			(layer "F.Fab")
		)
		(fp_line
			(start -0.12065 0.3048)
			(end -0.67945 0.3048)
			(stroke
				(width 0.1)
				(type default)
			)
			(layer "F.Fab")
		)
		(fp_line
			(start 0.120396 0.2794)
			(end -0.12065 0.2794)
			(stroke
				(width 0.1)
				(type default)
			)
			(layer "F.Fab")
		)
		(fp_line
			(start 0.120396 0.3048)
			(end 0.120396 0.2794)
			(stroke
				(width 0.1)
				(type default)
			)
			(layer "F.Fab")
		)
		(fp_line
			(start 0.12065 -0.3048)
			(end 0.67945 -0.3048)
			(stroke
				(width 0.1)
				(type default)
			)
			(layer "F.Fab")
		)
		(fp_line
			(start 0.12065 -0.2794)
			(end 0.12065 -0.3048)
			(stroke
				(width 0.1)
				(type default)
			)
			(layer "F.Fab")
		)
		(fp_line
			(start 0.67945 -0.3048)
			(end 0.67945 0.3048)
			(stroke
				(width 0.1)
				(type default)
			)
			(layer "F.Fab")
		)
		(fp_line
			(start 0.67945 0.3048)
			(end 0.120396 0.3048)
			(stroke
				(width 0.1)
				(type default)
			)
			(layer "F.Fab")
		)
		(pad "1" smd circle
			(at -0.40005 0)
			(size 0 0)
			(layers "F.Cu" "F.Mask" "F.Paste")
			(net "P3V3_AUX")
		)
		(pad "2" smd circle
			(at 0.40005 0)
			(size 0 0)
			(layers "F.Cu" "F.Mask" "F.Paste")
			(net "SMB_S3M_CPU1_3V3AUX_SCL")
		)
	)
)
